# T6G (Grand Teton) — schematic netlist excerpt (pin names and nets, part order shuffled) for the footprints in the layout excerpt that follows; sources: Cadence DE-HDL packaged netlist, KiCad conversion of 04192023_DAF0TMB3IC0_F0TG_MB_C_brd_V02_OCP.brd

R6756  Q_RES  0 5% CHIP  pkg 0201LF  page 184 : A = SMB_RT_CPU0_P1_SDA ; B = SMB_RT_CPU0_P1_R_SDA

J82  PICOPROBE_BXA  DELTA-L 4.0 EMPTY  pkg TRIANG_LAUNCH_3PXB  page 229
  \1_p\  = DELTA_L_85_10INCH_BOT_DN
  \2_n\  = DELTA_L_85_10INCH_BOT_DP
  \3_g\  = DELTA_L_GND_1

(kicad_pcb
	(version 20260206)
	(generator "pcbnew")
	(generator_version "10.0")
	(general
		(thickness 1.6)
		(legacy_teardrops no)
	)
	(paper "A4")
	(title_block
		(title "04192023_DAF0TMB3IC0_F0TG_MB_C_brd_V02_OCP.brd")
		(comment 1 "Grand Teton / footprints 5131-5132 of 8354")
	)
	(layers
		(0 "F.Cu" signal "TOP")
		(4 "In1.Cu" signal "GND")
		(6 "In2.Cu" signal "IN1")
		(8 "In3.Cu" signal "GND1")
		(10 "In4.Cu" signal "IN2")
		(12 "In5.Cu" signal "GND2")
		(14 "In6.Cu" signal "IN3")
		(16 "In7.Cu" signal "GND3")
		(18 "In8.Cu" signal "VCC")
		(20 "In9.Cu" signal "VCC1")
		(22 "In10.Cu" signal "GND4")
		(24 "In11.Cu" signal "IN4")
		(26 "In12.Cu" signal "GND5")
		(28 "In13.Cu" signal "IN5")
		(30 "In14.Cu" signal "GND6")
		(32 "In15.Cu" signal "IN6")
		(34 "In16.Cu" signal "GND7")
		(2 "B.Cu" signal "BOTTOM")
		(9 "F.Adhes" user "F.Adhesive")
		(11 "B.Adhes" user "B.Adhesive")
		(13 "F.Paste" user "Package Geometry/Pastemask Top")
		(15 "B.Paste" user "Package Geometry/Pastemask Bottom")
		(5 "F.SilkS" user "Ref Des/Silkscreen Top")
		(7 "B.SilkS" user "Ref Des/Silkscreen Bottom")
		(1 "F.Mask" user "Board Geometry/Soldermask Top")
		(3 "B.Mask" user "Board Geometry/Soldermask Bottom")
		(17 "Dwgs.User" user "User.Drawings")
		(19 "Cmts.User" user "User.Comments")
		(21 "Eco1.User" user "User.Eco1")
		(23 "Eco2.User" user "User.Eco2")
		(25 "Edge.Cuts" user "Board Geometry/Outline")
		(27 "Margin" user)
		(31 "F.CrtYd" user "Package Geometry/Place Bound Top")
		(29 "B.CrtYd" user "Package Geometry/Place Bound Bottom")
		(35 "F.Fab" user "Ref Des/Assembly Top")
		(33 "B.Fab" user "Ref Des/Assembly Bottom")
	)
	(footprint ""
		(layer "B.Cu")
		(at 230.6828 -339.598 180)
		(property "Reference" "R6756"
			(at 0 0 0)
			(layer "B.SilkS")
			(hide yes)
			(effects
				(font
					(size 1.27 1.27)
				)
				(justify mirror)
			)
		)
		(property "Value" ""
			(at 0 0 0)
			(layer "B.Fab")
			(effects
				(font
					(size 1.27 1.27)
				)
				(justify mirror)
			)
		)
		(duplicate_pad_numbers_are_jumpers no)
		(fp_line
			(start 0.32512 0.175006)
			(end 0.32512 -0.175006)
			(stroke
				(width 0.1)
				(type default)
			)
			(layer "B.Fab")
		)
		(fp_line
			(start 0.32512 -0.175006)
			(end -0.32512 -0.175006)
			(stroke
				(width 0.1)
				(type default)
			)
			(layer "B.Fab")
		)
		(fp_line
			(start -0.32512 0.175006)
			(end 0.32512 0.175006)
			(stroke
				(width 0.1)
				(type default)
			)
			(layer "B.Fab")
		)
		(fp_line
			(start -0.32512 -0.175006)
			(end -0.32512 0.175006)
			(stroke
				(width 0.1)
				(type default)
			)
			(layer "B.Fab")
		)
		(pad "1" smd rect
			(at 0.2667 0)
			(size 0.3048 0.381)
			(layers "B.Cu" "B.Mask" "B.Paste")
			(net "SMB_RT_CPU0_P1_SDA")
		)
		(pad "2" smd rect
			(at -0.2667 0 180)
			(size 0.3048 0.381)
			(layers "B.Cu" "B.Mask" "B.Paste")
			(net "SMB_RT_CPU0_P1_R_SDA")
		)
	)
	(footprint ""
		(layer "B.Cu")
		(at 300.538388 7.622794)
		(property "Reference" "J82"
			(at 4.445 1.171956 270)
			(unlocked yes)
			(layer "B.SilkS")
			(effects
				(font
					(size 0.7874 0.5842)
					(thickness 0.1524)
				)
				(justify left mirror)
			)
		)
		(property "Value" ""
			(at 0 0 0)
			(layer "B.Fab")
			(effects
				(font
					(size 1.27 1.27)
				)
				(justify mirror)
			)
		)
		(duplicate_pad_numbers_are_jumpers no)
		(fp_line
			(start -1.2192 -2.06756)
			(end -1.2192 2.06756)
			(stroke
				(width 0.1524)
				(type default)
			)
			(layer "B.SilkS")
		)
		(fp_line
			(start -1.2192 2.06756)
			(end 1.2192 2.06756)
			(stroke
				(width 0.1524)
				(type default)
			)
			(layer "B.SilkS")
		)
		(fp_line
			(start 1.2192 -2.06756)
			(end -1.2192 -2.06756)
			(stroke
				(width 0.1524)
				(type default)
			)
			(layer "B.SilkS")
		)
		(fp_line
			(start 1.2192 2.06756)
			(end 1.2192 -2.06756)
			(stroke
				(width 0.1524)
				(type default)
			)
			(layer "B.SilkS")
		)
		(pad "" np_thru_hole circle
			(at -3.4671 -1.27 270)
			(size 1.0414 1.0414)
			(drill 1.0414)
			(layers "*.Cu" "*.Mask")
			(clearance 0.381)
			(thermal_gap 0.381)
		)
		(pad "" np_thru_hole circle
			(at -3.4671 1.27 270)
			(size 1.0414 1.0414)
			(drill 1.0414)
			(layers "*.Cu" "*.Mask")
			(clearance 0.381)
			(thermal_gap 0.381)
		)
		(pad "" np_thru_hole circle
			(at 2.8829 -1.27 270)
			(size 1.0414 1.0414)
			(drill 1.0414)
			(layers "*.Cu" "*.Mask")
			(clearance 0.381)
			(thermal_gap 0.381)
		)
		(pad "" np_thru_hole circle
			(at 2.8829 1.27 270)
			(size 1.0414 1.0414)
			(drill 1.0414)
			(layers "*.Cu" "*.Mask")
			(clearance 0.381)
			(thermal_gap 0.381)
		)
		(pad "1" smd rect
			(at -0.8255 -0.249936 270)
			(size 0.3048 0.508)
			(layers "B.Cu" "B.Mask" "B.Paste")
			(net "DELTA_L_85_10INCH_BOT_DN")
		)
		(pad "2" smd rect
			(at -0.8255 0.249936 270)
			(size 0.3048 0.508)
			(layers "B.Cu" "B.Mask" "B.Paste")
			(net "DELTA_L_85_10INCH_BOT_DP")
		)
		(pad "3" smd circle
			(at 0 0 180)
			(size 0 0)
			(layers "B.Cu" "B.Mask" "B.Paste")
			(net "DELTA_L_GND_1")
		)
		(zone
			(layers "F.Cu" "B.Cu" "In1.Cu" "In2.Cu" "In3.Cu" "In4.Cu" "In5.Cu" "In6.Cu"
				"In7.Cu" "In8.Cu" "In9.Cu" "In10.Cu" "In11.Cu" "In12.Cu" "In13.Cu" "In14.Cu"
				"In15.Cu" "In16.Cu"
			)
			(hatch none 0.5)
			(connect_pads
				(clearance 0)
			)
			(min_thickness 0.25)
			(keepout
				(tracks not_allowed)
				(vias allowed)
				(pads allowed)
				(copperpour not_allowed)
				(footprints allowed)
			)
			(placement
				(enabled no)
				(sheetname "")
			)
			(fill
				(thermal_gap 0.5)
				(thermal_bridge_width 0.5)
				(island_removal_mode 0)
			)
			(polygon
				(pts
					(arc
						(start 297.998388 6.352794)
						(mid 296.144188 6.352794)
						(end 297.998388 6.352794)
					)
				)
			)
		)
		(zone
			(layers "F.Cu" "B.Cu" "In1.Cu" "In2.Cu" "In3.Cu" "In4.Cu" "In5.Cu" "In6.Cu"
				"In7.Cu" "In8.Cu" "In9.Cu" "In10.Cu" "In11.Cu" "In12.Cu" "In13.Cu" "In14.Cu"
				"In15.Cu" "In16.Cu"
			)
			(hatch none 0.5)
			(connect_pads
				(clearance 0)
			)
			(min_thickness 0.25)
			(keepout
				(tracks not_allowed)
				(vias allowed)
				(pads allowed)
				(copperpour not_allowed)
				(footprints allowed)
			)
			(placement
				(enabled no)
				(sheetname "")
			)
			(fill
				(thermal_gap 0.5)
				(thermal_bridge_width 0.5)
				(island_removal_mode 0)
			)
			(polygon
				(pts
					(arc
						(start 297.998388 8.892794)
						(mid 296.144188 8.892794)
						(end 297.998388 8.892794)
					)
				)
			)
		)
		(zone
			(layers "F.Cu" "B.Cu" "In1.Cu" "In2.Cu" "In3.Cu" "In4.Cu" "In5.Cu" "In6.Cu"
				"In7.Cu" "In8.Cu" "In9.Cu" "In10.Cu" "In11.Cu" "In12.Cu" "In13.Cu" "In14.Cu"
				"In15.Cu" "In16.Cu"
			)
			(hatch none 0.5)
			(connect_pads
				(clearance 0)
			)
			(min_thickness 0.25)
			(keepout
				(tracks not_allowed)
				(vias allowed)
				(pads allowed)
				(copperpour not_allowed)
				(footprints allowed)
			)
			(placement
				(enabled no)
				(sheetname "")
			)
			(fill
				(thermal_gap 0.5)
				(thermal_bridge_width 0.5)
				(island_removal_mode 0)
			)
			(polygon
				(pts
					(arc
						(start 304.348388 6.352794)
						(mid 302.494188 6.352794)
						(end 304.348388 6.352794)
					)
				)
			)
		)
		(zone
			(layers "F.Cu" "B.Cu" "In1.Cu" "In2.Cu" "In3.Cu" "In4.Cu" "In5.Cu" "In6.Cu"
				"In7.Cu" "In8.Cu" "In9.Cu" "In10.Cu" "In11.Cu" "In12.Cu" "In13.Cu" "In14.Cu"
				"In15.Cu" "In16.Cu"
			)
			(hatch none 0.5)
			(connect_pads
				(clearance 0)
			)
			(min_thickness 0.25)
			(keepout
				(tracks not_allowed)
				(vias allowed)
				(pads allowed)
				(copperpour not_allowed)
				(footprints allowed)
			)
			(placement
				(enabled no)
				(sheetname "")
			)
			(fill
				(thermal_gap 0.5)
				(thermal_bridge_width 0.5)
				(island_removal_mode 0)
			)
			(polygon
				(pts
					(arc
						(start 304.348388 8.892794)
						(mid 302.494188 8.892794)
						(end 304.348388 8.892794)
					)
				)
			)
		)
		(zone
			(layer "B.Cu")
			(hatch none 0.5)
			(connect_pads
				(clearance 0)
			)
			(min_thickness 0.25)
			(keepout
				(tracks not_allowed)
				(vias allowed)
				(pads allowed)
				(copperpour not_allowed)
				(footprints allowed)
			)
			(placement
				(enabled no)
				(sheetname "")
			)
			(fill
				(thermal_gap 0.5)
				(thermal_bridge_width 0.5)
				(island_removal_mode 0)
			)
			(polygon
				(pts
					(xy 299.420788 7.074154) (xy 299.420788 7.169658) (xy 300.017688 7.169658) (xy 300.017688 7.576058)
					(xy 299.420788 7.576058) (xy 299.420788 7.66953) (xy 300.017688 7.66953) (xy 300.017688 8.07593)
					(xy 299.420788 8.07593) (xy 299.420788 8.171434) (xy 300.119288 8.171434) (xy 300.119288 7.074154)
				)
			)
		)
	)
)
